# T6G (Grand Teton) — schematic netlist excerpt (pin names and nets, part order shuffled) for the footprints in the layout excerpt that follows; sources: Cadence DE-HDL packaged netlist, KiCad conversion of 04192023_DAF0TMB3IC0_F0TG_MB_C_brd_V02_OCP.brd

R1142  Q_RES  0 5% CHIP  pkg 0402LF  page 136 : A = OCP_V3_1_P3V3_PWRGD ; B = OCP_V3_1_P3V3_R2_PWRGD
R821  Q_RES  10K 5% CHIP  pkg 0402LF  page 164 : A = P3V3_AUX ; B = UART_VCC_J13

(kicad_pcb
	(version 20260206)
	(generator "pcbnew")
	(generator_version "10.0")
	(general
		(thickness 1.6)
		(legacy_teardrops no)
	)
	(paper "A4")
	(title_block
		(title "04192023_DAF0TMB3IC0_F0TG_MB_C_brd_V02_OCP.brd")
		(comment 1 "Grand Teton / footprints 268-269 of 8354")
	)
	(layers
		(0 "F.Cu" signal "TOP")
		(4 "In1.Cu" signal "GND")
		(6 "In2.Cu" signal "IN1")
		(8 "In3.Cu" signal "GND1")
		(10 "In4.Cu" signal "IN2")
		(12 "In5.Cu" signal "GND2")
		(14 "In6.Cu" signal "IN3")
		(16 "In7.Cu" signal "GND3")
		(18 "In8.Cu" signal "VCC")
		(20 "In9.Cu" signal "VCC1")
		(22 "In10.Cu" signal "GND4")
		(24 "In11.Cu" signal "IN4")
		(26 "In12.Cu" signal "GND5")
		(28 "In13.Cu" signal "IN5")
		(30 "In14.Cu" signal "GND6")
		(32 "In15.Cu" signal "IN6")
		(34 "In16.Cu" signal "GND7")
		(2 "B.Cu" signal "BOTTOM")
		(9 "F.Adhes" user "F.Adhesive")
		(11 "B.Adhes" user "B.Adhesive")
		(13 "F.Paste" user "Package Geometry/Pastemask Top")
		(15 "B.Paste" user "Package Geometry/Pastemask Bottom")
		(5 "F.SilkS" user "Ref Des/Silkscreen Top")
		(7 "B.SilkS" user "Ref Des/Silkscreen Bottom")
		(1 "F.Mask" user "Board Geometry/Soldermask Top")
		(3 "B.Mask" user "Board Geometry/Soldermask Bottom")
		(17 "Dwgs.User" user "User.Drawings")
		(19 "Cmts.User" user "User.Comments")
		(21 "Eco1.User" user "User.Eco1")
		(23 "Eco2.User" user "User.Eco2")
		(25 "Edge.Cuts" user "Board Geometry/Outline")
		(27 "Margin" user)
		(31 "F.CrtYd" user "Package Geometry/Place Bound Top")
		(29 "B.CrtYd" user "Package Geometry/Place Bound Bottom")
		(35 "F.Fab" user "Ref Des/Assembly Top")
		(33 "B.Fab" user "Ref Des/Assembly Bottom")
	)
	(footprint ""
		(layer "F.Cu")
		(at 169.220642 -92.268294 180)
		(property "Reference" "R1142"
			(at 0 0 180)
			(layer "F.SilkS")
			(hide yes)
			(effects
				(font
					(size 1.27 1.27)
				)
			)
		)
		(property "Value" ""
			(at 0 0 180)
			(layer "F.Fab")
			(effects
				(font
					(size 1.27 1.27)
				)
			)
		)
		(duplicate_pad_numbers_are_jumpers no)
		(fp_line
			(start 0.7874 0.4064)
			(end -0.7874 0.4064)
			(stroke
				(width 0.1524)
				(type default)
			)
			(layer "F.SilkS")
		)
		(fp_line
			(start 0.7874 -0.4064)
			(end 0.7874 0.4064)
			(stroke
				(width 0.1524)
				(type default)
			)
			(layer "F.SilkS")
		)
		(fp_line
			(start -0.7874 0.4064)
			(end -0.7874 -0.4064)
			(stroke
				(width 0.1524)
				(type default)
			)
			(layer "F.SilkS")
		)
		(fp_line
			(start -0.7874 -0.4064)
			(end 0.7874 -0.4064)
			(stroke
				(width 0.1524)
				(type default)
			)
			(layer "F.SilkS")
		)
		(fp_line
			(start 0.67945 0.3048)
			(end 0.120396 0.3048)
			(stroke
				(width 0.1)
				(type default)
			)
			(layer "F.Fab")
		)
		(fp_line
			(start 0.67945 -0.3048)
			(end 0.67945 0.3048)
			(stroke
				(width 0.1)
				(type default)
			)
			(layer "F.Fab")
		)
		(fp_line
			(start 0.12065 -0.2794)
			(end 0.12065 -0.3048)
			(stroke
				(width 0.1)
				(type default)
			)
			(layer "F.Fab")
		)
		(fp_line
			(start 0.12065 -0.3048)
			(end 0.67945 -0.3048)
			(stroke
				(width 0.1)
				(type default)
			)
			(layer "F.Fab")
		)
		(fp_line
			(start 0.120396 0.3048)
			(end 0.120396 0.2794)
			(stroke
				(width 0.1)
				(type default)
			)
			(layer "F.Fab")
		)
		(fp_line
			(start 0.120396 0.2794)
			(end -0.12065 0.2794)
			(stroke
				(width 0.1)
				(type default)
			)
			(layer "F.Fab")
		)
		(fp_line
			(start -0.12065 0.3048)
			(end -0.67945 0.3048)
			(stroke
				(width 0.1)
				(type default)
			)
			(layer "F.Fab")
		)
		(fp_line
			(start -0.12065 0.2794)
			(end -0.12065 0.3048)
			(stroke
				(width 0.1)
				(type default)
			)
			(layer "F.Fab")
		)
		(fp_line
			(start -0.12065 -0.2794)
			(end 0.12065 -0.2794)
			(stroke
				(width 0.1)
				(type default)
			)
			(layer "F.Fab")
		)
		(fp_line
			(start -0.12065 -0.305054)
			(end -0.12065 -0.2794)
			(stroke
				(width 0.1)
				(type default)
			)
			(layer "F.Fab")
		)
		(fp_line
			(start -0.67945 0.3048)
			(end -0.67945 -0.305054)
			(stroke
				(width 0.1)
				(type default)
			)
			(layer "F.Fab")
		)
		(fp_line
			(start -0.67945 -0.305054)
			(end -0.12065 -0.305054)
			(stroke
				(width 0.1)
				(type default)
			)
			(layer "F.Fab")
		)
		(pad "1" smd circle
			(at -0.40005 0 180)
			(size 0 0)
			(layers "F.Cu" "F.Mask" "F.Paste")
			(net "OCP_V3_1_P3V3_PWRGD")
		)
		(pad "2" smd circle
			(at 0.40005 0 180)
			(size 0 0)
			(layers "F.Cu" "F.Mask" "F.Paste")
			(net "OCP_V3_1_P3V3_R2_PWRGD")
		)
	)
	(footprint ""
		(layer "F.Cu")
		(at 364.302548 -14.450568 90)
		(property "Reference" "R821"
			(at 0 0 90)
			(layer "F.SilkS")
			(hide yes)
			(effects
				(font
					(size 1.27 1.27)
				)
			)
		)
		(property "Value" ""
			(at 0 0 90)
			(layer "F.Fab")
			(effects
				(font
					(size 1.27 1.27)
				)
			)
		)
		(duplicate_pad_numbers_are_jumpers no)
		(fp_line
			(start 0.7874 -0.4064)
			(end 0.7874 0.4064)
			(stroke
				(width 0.1524)
				(type default)
			)
			(layer "F.SilkS")
		)
		(fp_line
			(start -0.7874 -0.4064)
			(end 0.7874 -0.4064)
			(stroke
				(width 0.1524)
				(type default)
			)
			(layer "F.SilkS")
		)
		(fp_line
			(start 0.7874 0.4064)
			(end -0.7874 0.4064)
			(stroke
				(width 0.1524)
				(type default)
			)
			(layer "F.SilkS")
		)
		(fp_line
			(start -0.7874 0.4064)
			(end -0.7874 -0.4064)
			(stroke
				(width 0.1524)
				(type default)
			)
			(layer "F.SilkS")
		)
		(fp_line
			(start -0.12065 -0.305054)
			(end -0.12065 -0.2794)
			(stroke
				(width 0.1)
				(type default)
			)
			(layer "F.Fab")
		)
		(fp_line
			(start -0.67945 -0.305054)
			(end -0.12065 -0.305054)
			(stroke
				(width 0.1)
				(type default)
			)
			(layer "F.Fab")
		)
		(fp_line
			(start 0.67945 -0.3048)
			(end 0.67945 0.3048)
			(stroke
				(width 0.1)
				(type default)
			)
			(layer "F.Fab")
		)
		(fp_line
			(start 0.12065 -0.3048)
			(end 0.67945 -0.3048)
			(stroke
				(width 0.1)
				(type default)
			)
			(layer "F.Fab")
		)
		(fp_line
			(start 0.12065 -0.2794)
			(end 0.12065 -0.3048)
			(stroke
				(width 0.1)
				(type default)
			)
			(layer "F.Fab")
		)
		(fp_line
			(start -0.12065 -0.2794)
			(end 0.12065 -0.2794)
			(stroke
				(width 0.1)
				(type default)
			)
			(layer "F.Fab")
		)
		(fp_line
			(start 0.120396 0.2794)
			(end -0.12065 0.2794)
			(stroke
				(width 0.1)
				(type default)
			)
			(layer "F.Fab")
		)
		(fp_line
			(start -0.12065 0.2794)
			(end -0.12065 0.3048)
			(stroke
				(width 0.1)
				(type default)
			)
			(layer "F.Fab")
		)
		(fp_line
			(start 0.67945 0.3048)
			(end 0.120396 0.3048)
			(stroke
				(width 0.1)
				(type default)
			)
			(layer "F.Fab")
		)
		(fp_line
			(start 0.120396 0.3048)
			(end 0.120396 0.2794)
			(stroke
				(width 0.1)
				(type default)
			)
			(layer "F.Fab")
		)
		(fp_line
			(start -0.12065 0.3048)
			(end -0.67945 0.3048)
			(stroke
				(width 0.1)
				(type default)
			)
			(layer "F.Fab")
		)
		(fp_line
			(start -0.67945 0.3048)
			(end -0.67945 -0.305054)
			(stroke
				(width 0.1)
				(type default)
			)
			(layer "F.Fab")
		)
		(pad "1" smd circle
			(at -0.40005 0 90)
			(size 0 0)
			(layers "F.Cu" "F.Mask" "F.Paste")
			(net "P3V3_AUX")
		)
		(pad "2" smd circle
			(at 0.40005 0 90)
			(size 0 0)
			(layers "F.Cu" "F.Mask" "F.Paste")
			(net "UART_VCC_J13")
		)
	)
)
